(kicad_pcb
	(version 20260206)
	(generator "pcbnew")
	(generator_version "10.0")
	(general
		(thickness 1.6)
		(legacy_teardrops no)
	)
	(paper "A4")
	(title_block
		(title "v1-chassis-manager — T6M_CM_d_v01_1031_1645.brd")
		(comment 1 "Open CloudServer (Microsoft) / footprints 1660-1669 of 2512")
	)
	(layers
		(0 "F.Cu" signal "TOP")
		(4 "In1.Cu" signal "GND1")
		(6 "In2.Cu" signal "IN1")
		(8 "In3.Cu" signal "VCC1")
		(10 "In4.Cu" signal "VCC2")
		(12 "In5.Cu" signal "GND2")
		(14 "In6.Cu" signal "IN2")
		(16 "In7.Cu" signal "IN3")
		(18 "In8.Cu" signal "GND3")
		(2 "B.Cu" signal "BOTTOM")
		(9 "F.Adhes" user "F.Adhesive")
		(11 "B.Adhes" user "B.Adhesive")
		(13 "F.Paste" user "Package Geometry/Pastemask Top")
		(15 "B.Paste" user "Package Geometry/Pastemask Bottom")
		(5 "F.SilkS" user "Ref Des/Silkscreen Top")
		(7 "B.SilkS" user "Ref Des/Silkscreen Bottom")
		(1 "F.Mask" user "Board Geometry/Soldermask Top")
		(3 "B.Mask" user "Board Geometry/Soldermask Bottom")
		(17 "Dwgs.User" user "User.Drawings")
		(19 "Cmts.User" user "User.Comments")
		(21 "Eco1.User" user "User.Eco1")
		(23 "Eco2.User" user "User.Eco2")
		(25 "Edge.Cuts" user "Board Geometry/Outline")
		(27 "Margin" user)
		(31 "F.CrtYd" user "Package Geometry/Place Bound Top")
		(29 "B.CrtYd" user "Package Geometry/Place Bound Bottom")
		(35 "F.Fab" user "Ref Des/Assembly Top")
		(33 "B.Fab" user "Ref Des/Assembly Bottom")
	)
	(footprint ""
		(layer "B.Cu")
		(at 40.376602 -155.176982)
		(property "Reference" "C403"
			(at -6.396482 -9.777984 0)
			(unlocked yes)
			(layer "B.SilkS")
			(effects
				(font
					(size 0.7874 0.5842)
					(thickness 0.1524)
				)
				(justify left mirror)
			)
		)
		(property "Value" ""
			(at 0 0 0)
			(layer "B.Fab")
			(effects
				(font
					(size 1.27 1.27)
				)
				(justify mirror)
			)
		)
		(duplicate_pad_numbers_are_jumpers no)
		(fp_line
			(start -0.7874 -0.4064)
			(end -0.7874 0.4064)
			(stroke
				(width 0.1524)
				(type default)
			)
			(layer "B.SilkS")
		)
		(fp_line
			(start -0.7874 0.4064)
			(end 0.7874 0.4064)
			(stroke
				(width 0.1524)
				(type default)
			)
			(layer "B.SilkS")
		)
		(fp_line
			(start 0 0.381)
			(end 0 -0.381)
			(stroke
				(width 0.1524)
				(type default)
			)
			(layer "B.SilkS")
		)
		(fp_line
			(start 0.7874 -0.4064)
			(end -0.7874 -0.4064)
			(stroke
				(width 0.1524)
				(type default)
			)
			(layer "B.SilkS")
		)
		(fp_line
			(start 0.7874 0.4064)
			(end 0.7874 -0.4064)
			(stroke
				(width 0.1524)
				(type default)
			)
			(layer "B.SilkS")
		)
		(fp_poly
			(pts
				(xy 0.5334 0.254) (xy 0.635 0.254) (xy 0.635 0.2286) (xy 0.635 -0.254) (xy 0.5334 -0.254) (xy 0.5334 -0.2794)
				(xy -0.5334 -0.2794) (xy -0.5334 -0.254) (xy -0.635 -0.254) (xy -0.635 0.254) (xy -0.5334 0.254)
				(xy -0.5334 0.2794) (xy 0.508 0.2794) (xy 0.5334 0.2794)
			)
			(stroke
				(width 0)
				(type default)
			)
			(fill no)
			(layer "B.CrtYd")
		)
		(pad "1" smd rect
			(at -0.40005 0 180)
			(size 0.4572 0.508)
			(layers "B.Cu" "B.Mask" "B.Paste")
			(net "P1V9_LAN1")
		)
		(pad "2" smd rect
			(at 0.40005 0 180)
			(size 0.4572 0.508)
			(layers "B.Cu" "B.Mask" "B.Paste")
			(net "GND")
		)
	)
	(footprint ""
		(layer "B.Cu")
		(at 78.83144 -175.553624 180)
		(property "Reference" "R694"
			(at -30.562296 -20.108164 0)
			(unlocked yes)
			(layer "B.SilkS")
			(effects
				(font
					(size 0.7874 0.5842)
					(thickness 0.1524)
				)
				(justify left mirror)
			)
		)
		(property "Value" ""
			(at 0 0 0)
			(layer "B.Fab")
			(effects
				(font
					(size 1.27 1.27)
				)
				(justify mirror)
			)
		)
		(duplicate_pad_numbers_are_jumpers no)
		(fp_line
			(start 0.7874 0.4064)
			(end 0.7874 -0.4064)
			(stroke
				(width 0.1524)
				(type default)
			)
			(layer "B.SilkS")
		)
		(fp_line
			(start 0.7874 -0.4064)
			(end -0.7874 -0.4064)
			(stroke
				(width 0.1524)
				(type default)
			)
			(layer "B.SilkS")
		)
		(fp_line
			(start -0.7874 0.4064)
			(end 0.7874 0.4064)
			(stroke
				(width 0.1524)
				(type default)
			)
			(layer "B.SilkS")
		)
		(fp_line
			(start -0.7874 -0.4064)
			(end -0.7874 0.4064)
			(stroke
				(width 0.1524)
				(type default)
			)
			(layer "B.SilkS")
		)
		(fp_poly
			(pts
				(xy 0.508 0.2794) (xy 0.508 0.2286) (xy 0.635 0.2286) (xy 0.635 -0.254) (xy 0.5334 -0.254) (xy 0.5334 -0.2794)
				(xy -0.5334 -0.2794) (xy -0.5334 -0.254) (xy -0.635 -0.254) (xy -0.635 0.254) (xy -0.5334 0.254)
				(xy -0.5334 0.2794)
			)
			(stroke
				(width 0)
				(type default)
			)
			(fill no)
			(layer "B.CrtYd")
		)
		(pad "1" smd rect
			(at -0.40005 0)
			(size 0.4572 0.508)
			(layers "B.Cu" "B.Mask" "B.Paste")
			(net "T2_NODE2_EN")
		)
		(pad "2" smd rect
			(at 0.40005 0)
			(size 0.4572 0.508)
			(layers "B.Cu" "B.Mask" "B.Paste")
			(net "P5V_NODE1")
		)
	)
	(footprint ""
		(layer "B.Cu")
		(at 59.636406 -72.479154 90)
		(property "Reference" "C128"
			(at -33.578292 -14.517116 270)
			(unlocked yes)
			(layer "B.SilkS")
			(effects
				(font
					(size 0.7874 0.5842)
					(thickness 0.1524)
				)
				(justify left mirror)
			)
		)
		(property "Value" ""
			(at 0 0 90)
			(layer "B.Fab")
			(effects
				(font
					(size 1.27 1.27)
				)
				(justify mirror)
			)
		)
		(duplicate_pad_numbers_are_jumpers no)
		(fp_line
			(start 0.7874 -0.4064)
			(end -0.7874 -0.4064)
			(stroke
				(width 0.1524)
				(type default)
			)
			(layer "B.SilkS")
		)
		(fp_line
			(start -0.7874 -0.4064)
			(end -0.7874 0.4064)
			(stroke
				(width 0.1524)
				(type default)
			)
			(layer "B.SilkS")
		)
		(fp_line
			(start 0 0.381)
			(end 0 -0.381)
			(stroke
				(width 0.1524)
				(type default)
			)
			(layer "B.SilkS")
		)
		(fp_line
			(start 0.7874 0.4064)
			(end 0.7874 -0.4064)
			(stroke
				(width 0.1524)
				(type default)
			)
			(layer "B.SilkS")
		)
		(fp_line
			(start -0.7874 0.4064)
			(end 0.7874 0.4064)
			(stroke
				(width 0.1524)
				(type default)
			)
			(layer "B.SilkS")
		)
		(fp_poly
			(pts
				(xy 0.5334 0.254) (xy 0.635 0.254) (xy 0.635 0.2286) (xy 0.635 -0.254) (xy 0.5334 -0.254) (xy 0.5334 -0.2794)
				(xy -0.5334 -0.2794) (xy -0.5334 -0.254) (xy -0.635 -0.254) (xy -0.635 0.254) (xy -0.5334 0.254)
				(xy -0.5334 0.2794) (xy 0.508 0.2794) (xy 0.5334 0.2794)
			)
			(stroke
				(width 0)
				(type default)
			)
			(fill no)
			(layer "B.CrtYd")
		)
		(pad "1" smd rect
			(at -0.40005 0 270)
			(size 0.4572 0.508)
			(layers "B.Cu" "B.Mask" "B.Paste")
			(net "P1V05_NODE1")
		)
		(pad "2" smd rect
			(at 0.40005 0 270)
			(size 0.4572 0.508)
			(layers "B.Cu" "B.Mask" "B.Paste")
			(net "GND")
		)
	)
	(footprint ""
		(layer "B.Cu")
		(at 56.392572 -71.751698 -90)
		(property "Reference" "L7"
			(at 31.697168 14.069822 270)
			(unlocked yes)
			(layer "B.SilkS")
			(effects
				(font
					(size 0.7874 0.5842)
					(thickness 0.1524)
				)
				(justify left mirror)
			)
		)
		(property "Value" ""
			(at 0 0 90)
			(layer "B.Fab")
			(effects
				(font
					(size 1.27 1.27)
				)
				(justify mirror)
			)
		)
		(duplicate_pad_numbers_are_jumpers no)
		(fp_line
			(start -0.7874 0.4064)
			(end 0.7874 0.4064)
			(stroke
				(width 0.1524)
				(type default)
			)
			(layer "B.SilkS")
		)
		(fp_line
			(start -0.0889 0.4064)
			(end -0.0889 -0.4064)
			(stroke
				(width 0.1524)
				(type default)
			)
			(layer "B.SilkS")
		)
		(fp_line
			(start 0.0889 0.4064)
			(end 0.0889 -0.4064)
			(stroke
				(width 0.1524)
				(type default)
			)
			(layer "B.SilkS")
		)
		(fp_line
			(start 0.7874 0.4064)
			(end 0.7874 -0.4064)
			(stroke
				(width 0.1524)
				(type default)
			)
			(layer "B.SilkS")
		)
		(fp_line
			(start -0.7874 -0.4064)
			(end -0.7874 0.4064)
			(stroke
				(width 0.1524)
				(type default)
			)
			(layer "B.SilkS")
		)
		(fp_line
			(start 0.7874 -0.4064)
			(end -0.7874 -0.4064)
			(stroke
				(width 0.1524)
				(type default)
			)
			(layer "B.SilkS")
		)
		(fp_poly
			(pts
				(xy 0.5334 0.254) (xy 0.635 0.254) (xy 0.635 0.2286) (xy 0.635 -0.254) (xy 0.5334 -0.254) (xy 0.5334 -0.2794)
				(xy -0.5334 -0.2794) (xy -0.5334 -0.254) (xy -0.635 -0.254) (xy -0.635 0.254) (xy -0.5334 0.254)
				(xy -0.5334 0.2794) (xy 0.508 0.2794) (xy 0.5334 0.2794)
			)
			(stroke
				(width 0)
				(type default)
			)
			(fill no)
			(layer "B.CrtYd")
		)
		(pad "1" smd rect
			(at -0.40005 0 90)
			(size 0.4572 0.508)
			(layers "B.Cu" "B.Mask" "B.Paste")
			(net "P1V05_NODE1")
		)
		(pad "2" smd rect
			(at 0.40005 0 90)
			(size 0.4572 0.508)
			(layers "B.Cu" "B.Mask" "B.Paste")
			(net "P1V05_VCCACLK_DDR3_NODE1")
		)
	)
	(footprint ""
		(layer "B.Cu")
		(at 129.918968 -166.371778)
		(property "Reference" "R1000"
			(at -1.988312 -0.457454 0)
			(unlocked yes)
			(layer "B.SilkS")
			(effects
				(font
					(size 0.7874 0.5842)
					(thickness 0.1524)
				)
				(justify left mirror)
			)
		)
		(property "Value" ""
			(at 0 0 0)
			(layer "B.Fab")
			(effects
				(font
					(size 1.27 1.27)
				)
				(justify mirror)
			)
		)
		(duplicate_pad_numbers_are_jumpers no)
		(fp_line
			(start -0.7874 -0.4064)
			(end -0.7874 0.4064)
			(stroke
				(width 0.1524)
				(type default)
			)
			(layer "B.SilkS")
		)
		(fp_line
			(start -0.7874 0.4064)
			(end 0.7874 0.4064)
			(stroke
				(width 0.1524)
				(type default)
			)
			(layer "B.SilkS")
		)
		(fp_line
			(start 0.7874 -0.4064)
			(end -0.7874 -0.4064)
			(stroke
				(width 0.1524)
				(type default)
			)
			(layer "B.SilkS")
		)
		(fp_line
			(start 0.7874 0.4064)
			(end 0.7874 -0.4064)
			(stroke
				(width 0.1524)
				(type default)
			)
			(layer "B.SilkS")
		)
		(fp_poly
			(pts
				(xy 0.508 0.2794) (xy 0.508 0.2286) (xy 0.635 0.2286) (xy 0.635 -0.254) (xy 0.5334 -0.254) (xy 0.5334 -0.2794)
				(xy -0.5334 -0.2794) (xy -0.5334 -0.254) (xy -0.635 -0.254) (xy -0.635 0.254) (xy -0.5334 0.254)
				(xy -0.5334 0.2794)
			)
			(stroke
				(width 0)
				(type default)
			)
			(fill no)
			(layer "B.CrtYd")
		)
		(pad "1" smd rect
			(at -0.40005 0 180)
			(size 0.4572 0.508)
			(layers "B.Cu" "B.Mask" "B.Paste")
			(net "UART_T8_NODE4_TXD")
		)
		(pad "2" smd rect
			(at 0.40005 0 180)
			(size 0.4572 0.508)
			(layers "B.Cu" "B.Mask" "B.Paste")
			(net "UART_T8_NODE4_TXD_R")
		)
	)
	(footprint ""
		(layer "B.Cu")
		(at 60.057538 -81.309718)
		(property "Reference" "C41"
			(at -13.557758 30.810454 0)
			(unlocked yes)
			(layer "B.SilkS")
			(effects
				(font
					(size 0.7874 0.5842)
					(thickness 0.1524)
				)
				(justify left mirror)
			)
		)
		(property "Value" ""
			(at 0 0 0)
			(layer "B.Fab")
			(effects
				(font
					(size 1.27 1.27)
				)
				(justify mirror)
			)
		)
		(duplicate_pad_numbers_are_jumpers no)
		(fp_line
			(start -0.7874 -0.4064)
			(end -0.7874 0.4064)
			(stroke
				(width 0.1524)
				(type default)
			)
			(layer "B.SilkS")
		)
		(fp_line
			(start -0.7874 0.4064)
			(end 0.7874 0.4064)
			(stroke
				(width 0.1524)
				(type default)
			)
			(layer "B.SilkS")
		)
		(fp_line
			(start 0 0.381)
			(end 0 -0.381)
			(stroke
				(width 0.1524)
				(type default)
			)
			(layer "B.SilkS")
		)
		(fp_line
			(start 0.7874 -0.4064)
			(end -0.7874 -0.4064)
			(stroke
				(width 0.1524)
				(type default)
			)
			(layer "B.SilkS")
		)
		(fp_line
			(start 0.7874 0.4064)
			(end 0.7874 -0.4064)
			(stroke
				(width 0.1524)
				(type default)
			)
			(layer "B.SilkS")
		)
		(fp_poly
			(pts
				(xy 0.5334 0.254) (xy 0.635 0.254) (xy 0.635 0.2286) (xy 0.635 -0.254) (xy 0.5334 -0.254) (xy 0.5334 -0.2794)
				(xy -0.5334 -0.2794) (xy -0.5334 -0.254) (xy -0.635 -0.254) (xy -0.635 0.254) (xy -0.5334 0.254)
				(xy -0.5334 0.2794) (xy 0.508 0.2794) (xy 0.5334 0.2794)
			)
			(stroke
				(width 0)
				(type default)
			)
			(fill no)
			(layer "B.CrtYd")
		)
		(pad "1" smd rect
			(at -0.40005 0 180)
			(size 0.4572 0.508)
			(layers "B.Cu" "B.Mask" "B.Paste")
			(net "P3V3_NODE1")
		)
		(pad "2" smd rect
			(at 0.40005 0 180)
			(size 0.4572 0.508)
			(layers "B.Cu" "B.Mask" "B.Paste")
			(net "GND")
		)
	)
	(footprint ""
		(layer "B.Cu")
		(at 48.75022 -154.39009 180)
		(property "Reference" "C410"
			(at 11.81354 5.305806 0)
			(unlocked yes)
			(layer "B.SilkS")
			(effects
				(font
					(size 0.7874 0.5842)
					(thickness 0.1524)
				)
				(justify left mirror)
			)
		)
		(property "Value" ""
			(at 0 0 0)
			(layer "B.Fab")
			(effects
				(font
					(size 1.27 1.27)
				)
				(justify mirror)
			)
		)
		(duplicate_pad_numbers_are_jumpers no)
		(fp_line
			(start 0.7874 0.4064)
			(end 0.7874 -0.4064)
			(stroke
				(width 0.1524)
				(type default)
			)
			(layer "B.SilkS")
		)
		(fp_line
			(start 0.7874 -0.4064)
			(end -0.7874 -0.4064)
			(stroke
				(width 0.1524)
				(type default)
			)
			(layer "B.SilkS")
		)
		(fp_line
			(start 0 0.381)
			(end 0 -0.381)
			(stroke
				(width 0.1524)
				(type default)
			)
			(layer "B.SilkS")
		)
		(fp_line
			(start -0.7874 0.4064)
			(end 0.7874 0.4064)
			(stroke
				(width 0.1524)
				(type default)
			)
			(layer "B.SilkS")
		)
		(fp_line
			(start -0.7874 -0.4064)
			(end -0.7874 0.4064)
			(stroke
				(width 0.1524)
				(type default)
			)
			(layer "B.SilkS")
		)
		(fp_poly
			(pts
				(xy 0.5334 0.254) (xy 0.635 0.254) (xy 0.635 0.2286) (xy 0.635 -0.254) (xy 0.5334 -0.254) (xy 0.5334 -0.2794)
				(xy -0.5334 -0.2794) (xy -0.5334 -0.254) (xy -0.635 -0.254) (xy -0.635 0.254) (xy -0.5334 0.254)
				(xy -0.5334 0.2794) (xy 0.508 0.2794) (xy 0.5334 0.2794)
			)
			(stroke
				(width 0)
				(type default)
			)
			(fill no)
			(layer "B.CrtYd")
		)
		(pad "1" smd rect
			(at -0.40005 0)
			(size 0.4572 0.508)
			(layers "B.Cu" "B.Mask" "B.Paste")
			(net "P1V9_LAN1")
		)
		(pad "2" smd rect
			(at 0.40005 0)
			(size 0.4572 0.508)
			(layers "B.Cu" "B.Mask" "B.Paste")
			(net "GND")
		)
	)
	(footprint ""
		(layer "B.Cu")
		(at 59.771026 -119.048022 90)
		(property "Reference" "R332"
			(at -5.421122 0.029464 270)
			(unlocked yes)
			(layer "B.SilkS")
			(effects
				(font
					(size 0.7874 0.5842)
					(thickness 0.1524)
				)
				(justify left mirror)
			)
		)
		(property "Value" ""
			(at 0 0 90)
			(layer "B.Fab")
			(effects
				(font
					(size 1.27 1.27)
				)
				(justify mirror)
			)
		)
		(duplicate_pad_numbers_are_jumpers no)
		(fp_line
			(start 0.7874 -0.4064)
			(end -0.7874 -0.4064)
			(stroke
				(width 0.1524)
				(type default)
			)
			(layer "B.SilkS")
		)
		(fp_line
			(start -0.7874 -0.4064)
			(end -0.7874 0.4064)
			(stroke
				(width 0.1524)
				(type default)
			)
			(layer "B.SilkS")
		)
		(fp_line
			(start 0.7874 0.4064)
			(end 0.7874 -0.4064)
			(stroke
				(width 0.1524)
				(type default)
			)
			(layer "B.SilkS")
		)
		(fp_line
			(start -0.7874 0.4064)
			(end 0.7874 0.4064)
			(stroke
				(width 0.1524)
				(type default)
			)
			(layer "B.SilkS")
		)
		(fp_poly
			(pts
				(xy 0.508 0.2794) (xy 0.508 0.2286) (xy 0.635 0.2286) (xy 0.635 -0.254) (xy 0.5334 -0.254) (xy 0.5334 -0.2794)
				(xy -0.5334 -0.2794) (xy -0.5334 -0.254) (xy -0.635 -0.254) (xy -0.635 0.254) (xy -0.5334 0.254)
				(xy -0.5334 0.2794)
			)
			(stroke
				(width 0)
				(type default)
			)
			(fill no)
			(layer "B.CrtYd")
		)
		(pad "1" smd rect
			(at -0.40005 0 270)
			(size 0.4572 0.508)
			(layers "B.Cu" "B.Mask" "B.Paste")
			(net "P3V3_NODE1")
		)
		(pad "2" smd rect
			(at 0.40005 0 270)
			(size 0.4572 0.508)
			(layers "B.Cu" "B.Mask" "B.Paste")
			(net "BMC_ROMA16")
		)
	)
	(footprint ""
		(layer "B.Cu")
		(at 175.16348 -120.660668)
		(property "Reference" "C789"
			(at 9.948418 0.352298 0)
			(unlocked yes)
			(layer "B.SilkS")
			(effects
				(font
					(size 0.7874 0.5842)
					(thickness 0.1524)
				)
				(justify mirror)
			)
		)
		(property "Value" ""
			(at 0 0 0)
			(layer "B.Fab")
			(effects
				(font
					(size 1.27 1.27)
				)
				(justify mirror)
			)
		)
		(duplicate_pad_numbers_are_jumpers no)
		(fp_line
			(start -1.2954 -0.5842)
			(end -1.2954 0.5842)
			(stroke
				(width 0.1524)
				(type default)
			)
			(layer "B.SilkS")
		)
		(fp_line
			(start -1.2954 0.5842)
			(end 1.2954 0.5842)
			(stroke
				(width 0.1524)
				(type default)
			)
			(layer "B.SilkS")
		)
		(fp_line
			(start 0 -0.5842)
			(end 0 0.5842)
			(stroke
				(width 0.1524)
				(type default)
			)
			(layer "B.SilkS")
		)
		(fp_line
			(start 1.2954 -0.5842)
			(end -1.2954 -0.5842)
			(stroke
				(width 0.1524)
				(type default)
			)
			(layer "B.SilkS")
		)
		(fp_line
			(start 1.2954 0.5842)
			(end 1.2954 -0.5842)
			(stroke
				(width 0.1524)
				(type default)
			)
			(layer "B.SilkS")
		)
		(fp_poly
			(pts
				(xy -0.8636 -0.4572) (xy -0.8636 -0.3556) (xy -1.143 -0.3556) (xy -1.143 0.3556) (xy -0.8636 0.3556)
				(xy -0.8636 0.4572) (xy 0.8636 0.4572) (xy 0.8636 0.3556) (xy 1.143 0.3556) (xy 1.143 -0.3556) (xy 0.8636 -0.3556)
				(xy 0.8636 -0.4572)
			)
			(stroke
				(width 0)
				(type default)
			)
			(fill no)
			(layer "B.CrtYd")
		)
		(fp_line
			(start -0.884936 -0.504952)
			(end -0.884936 0.504952)
			(stroke
				(width 0.1)
				(type default)
			)
			(layer "B.Fab")
		)
		(fp_line
			(start -0.884936 0.504952)
			(end 0.884936 0.504952)
			(stroke
				(width 0.1)
				(type default)
			)
			(layer "B.Fab")
		)
		(fp_line
			(start 0.884936 -0.504952)
			(end -0.884936 -0.504952)
			(stroke
				(width 0.1)
				(type default)
			)
			(layer "B.Fab")
		)
		(fp_line
			(start 0.884936 0.504952)
			(end 0.884936 -0.504952)
			(stroke
				(width 0.1)
				(type default)
			)
			(layer "B.Fab")
		)
		(pad "1" smd rect
			(at -0.7366 0 90)
			(size 0.7112 0.8128)
			(layers "B.Cu" "B.Mask" "B.Paste")
			(net "P3V3_STB_NODE1")
		)
		(pad "2" smd rect
			(at 0.7366 0 90)
			(size 0.7112 0.8128)
			(layers "B.Cu" "B.Mask" "B.Paste")
			(net "GND")
		)
	)
	(footprint ""
		(layer "B.Cu")
		(at 153.604214 -62.075822 -90)
		(property "Reference" "C356"
			(at 2.829814 -6.116574 270)
			(unlocked yes)
			(layer "B.SilkS")
			(effects
				(font
					(size 0.7874 0.5842)
					(thickness 0.1524)
				)
				(justify left mirror)
			)
		)
		(property "Value" ""
			(at 0 0 90)
			(layer "B.Fab")
			(effects
				(font
					(size 1.27 1.27)
				)
				(justify mirror)
			)
		)
		(duplicate_pad_numbers_are_jumpers no)
		(fp_line
			(start -0.7874 0.4064)
			(end 0.7874 0.4064)
			(stroke
				(width 0.1524)
				(type default)
			)
			(layer "B.SilkS")
		)
		(fp_line
			(start 0.7874 0.4064)
			(end 0.7874 -0.4064)
			(stroke
				(width 0.1524)
				(type default)
			)
			(layer "B.SilkS")
		)
		(fp_line
			(start 0 0.381)
			(end 0 -0.381)
			(stroke
				(width 0.1524)
				(type default)
			)
			(layer "B.SilkS")
		)
		(fp_line
			(start -0.7874 -0.4064)
			(end -0.7874 0.4064)
			(stroke
				(width 0.1524)
				(type default)
			)
			(layer "B.SilkS")
		)
		(fp_line
			(start 0.7874 -0.4064)
			(end -0.7874 -0.4064)
			(stroke
				(width 0.1524)
				(type default)
			)
			(layer "B.SilkS")
		)
		(fp_poly
			(pts
				(xy 0.5334 0.254) (xy 0.635 0.254) (xy 0.635 0.2286) (xy 0.635 -0.254) (xy 0.5334 -0.254) (xy 0.5334 -0.2794)
				(xy -0.5334 -0.2794) (xy -0.5334 -0.254) (xy -0.635 -0.254) (xy -0.635 0.254) (xy -0.5334 0.254)
				(xy -0.5334 0.2794) (xy 0.508 0.2794) (xy 0.5334 0.2794)
			)
			(stroke
				(width 0)
				(type default)
			)
			(fill no)
			(layer "B.CrtYd")
		)
		(pad "1" smd rect
			(at -0.40005 0 90)
			(size 0.4572 0.508)
			(layers "B.Cu" "B.Mask" "B.Paste")
			(net "P1V8_SATA_VAA2_1_NODE1")
		)
		(pad "2" smd rect
			(at 0.40005 0 90)
			(size 0.4572 0.508)
			(layers "B.Cu" "B.Mask" "B.Paste")
			(net "GND")
		)
	)
)
